(kicad_pcb
	(version 20260206)
	(generator "pcbnew")
	(generator_version "10.0")
	(general
		(thickness 1.6)
		(legacy_teardrops no)
	)
	(paper "A4")
	(title_block
		(title "timecard-production-celestica-r4006 — R4006-B0001-02_R01.brd")
		(comment 1 "Time Appliance Project (Time Card) / footprints 246-249 of 1113")
	)
	(layers
		(0 "F.Cu" signal "TOP")
		(4 "In1.Cu" signal "L02_GND1")
		(6 "In2.Cu" signal "L03_SIG1")
		(8 "In3.Cu" signal "L04_GND2")
		(10 "In4.Cu" signal "L05_VCC1")
		(12 "In5.Cu" signal "L06_VCC2")
		(14 "In6.Cu" signal "L07_GND3")
		(16 "In7.Cu" signal "L08_SIG2")
		(18 "In8.Cu" signal "L09_GND4")
		(2 "B.Cu" signal "BOTTOM")
		(9 "F.Adhes" user "F.Adhesive")
		(11 "B.Adhes" user "B.Adhesive")
		(13 "F.Paste" user "Package Geometry/Pastemask Top")
		(15 "B.Paste" user "Package Geometry/Pastemask Bottom")
		(5 "F.SilkS" user "Ref Des/Silkscreen Top")
		(7 "B.SilkS" user "Ref Des/Silkscreen Bottom")
		(1 "F.Mask" user "Board Geometry/Soldermask Top")
		(3 "B.Mask" user "Board Geometry/Soldermask Bottom")
		(17 "Dwgs.User" user "User.Drawings")
		(19 "Cmts.User" user "User.Comments")
		(21 "Eco1.User" user "User.Eco1")
		(23 "Eco2.User" user "User.Eco2")
		(25 "Edge.Cuts" user "Board Geometry/Outline")
		(27 "Margin" user)
		(31 "F.CrtYd" user "Package Geometry/Place Bound Top")
		(29 "B.CrtYd" user "Package Geometry/Place Bound Bottom")
		(35 "F.Fab" user "Ref Des/Assembly Top")
		(33 "B.Fab" user "Ref Des/Assembly Bottom")
	)
	(footprint ""
		(layer "F.Cu")
		(at 131.953 -64.0334 180)
		(property "Reference" "C195"
			(at -0.381 -3.36677 0)
			(unlocked yes)
			(layer "F.SilkS")
			(effects
				(font
					(size 0.7874 0.5842)
					(thickness 0.1524)
				)
			)
		)
		(property "Value" "VAL*"
			(at 0.0762 3.134106 180)
			(unlocked yes)
			(layer "F.Fab")
			(hide yes)
			(effects
				(font
					(size 0.7874 0.5842)
					(thickness 0.1524)
				)
			)
		)
		(property "Tolerance" "TOL*"
			(at 0.0762 4.048506 180)
			(unlocked yes)
			(layer "Cmts.User")
			(hide yes)
			(effects
				(font
					(size 0.7874 0.5842)
					(thickness 0.1524)
				)
			)
		)
		(property "User Part Number" "PARTNUM*"
			(at 0.1016 5.013706 180)
			(unlocked yes)
			(layer "Cmts.User")
			(hide yes)
			(effects
				(font
					(size 0.7874 0.5842)
					(thickness 0.1524)
				)
			)
		)
		(property "Device Type" "CAPACITOR-G107-0F106-EM,10UF,2A"
			(at 0.0508 2.194306 180)
			(unlocked yes)
			(layer "F.Fab")
			(hide yes)
			(effects
				(font
					(size 0.7874 0.5842)
					(thickness 0.1524)
				)
			)
		)
		(duplicate_pad_numbers_are_jumpers no)
		(fp_line
			(start 1.5748 0.9398)
			(end 1.5748 -0.9398)
			(stroke
				(width 0.1)
				(type default)
			)
			(layer "F.SilkS")
		)
		(fp_line
			(start 1.5748 -0.9398)
			(end -1.5748 -0.9398)
			(stroke
				(width 0.1)
				(type default)
			)
			(layer "F.SilkS")
		)
		(fp_line
			(start -1.5748 0.9398)
			(end 1.5748 0.9398)
			(stroke
				(width 0.1)
				(type default)
			)
			(layer "F.SilkS")
		)
		(fp_line
			(start -1.5748 -0.9398)
			(end -1.5748 0.9398)
			(stroke
				(width 0.1)
				(type default)
			)
			(layer "F.SilkS")
		)
		(fp_rect
			(start -1.5748 0.9398)
			(end 1.5748 -0.9398)
			(stroke
				(width 0)
				(type default)
			)
			(fill no)
			(layer "F.CrtYd")
		)
		(fp_line
			(start 1.016 0.635)
			(end 1.016 -0.635)
			(stroke
				(width 0.1)
				(type default)
			)
			(layer "F.Fab")
		)
		(fp_line
			(start 1.016 -0.635)
			(end -1.016 -0.635)
			(stroke
				(width 0.1)
				(type default)
			)
			(layer "F.Fab")
		)
		(fp_line
			(start -1.016 0.635)
			(end 1.016 0.635)
			(stroke
				(width 0.1)
				(type default)
			)
			(layer "F.Fab")
		)
		(fp_line
			(start -1.016 -0.635)
			(end -1.016 0.635)
			(stroke
				(width 0.1)
				(type default)
			)
			(layer "F.Fab")
		)
		(pad "1" smd rect
			(at -0.8382 0 180)
			(size 0.9652 1.3716)
			(layers "F.Cu" "F.Mask" "F.Paste")
			(net "XP1R8V_FPGA")
		)
		(pad "2" smd rect
			(at 0.8382 0 180)
			(size 0.9652 1.3716)
			(layers "F.Cu" "F.Mask" "F.Paste")
			(net "SG")
		)
		(zone
			(layer "F.Cu")
			(hatch none 0.5)
			(connect_pads
				(clearance 0)
			)
			(min_thickness 0.25)
			(keepout
				(tracks allowed)
				(vias not_allowed)
				(pads allowed)
				(copperpour not_allowed)
				(footprints allowed)
			)
			(placement
				(enabled no)
				(sheetname "")
			)
			(fill
				(thermal_gap 0.5)
				(thermal_bridge_width 0.5)
				(island_removal_mode 0)
			)
			(polygon
				(pts
					(xy 132.1816 -64.6684) (xy 131.7244 -64.6684) (xy 131.7244 -63.3984) (xy 132.1816 -63.3984)
				)
			)
		)
	)
	(footprint ""
		(layer "F.Cu")
		(at 142.875 -17.2466)
		(property "Reference" "U25"
			(at -0.254 2.68097 0)
			(unlocked yes)
			(layer "F.SilkS")
			(effects
				(font
					(size 0.7874 0.5842)
					(thickness 0.1524)
				)
			)
		)
		(property "Value" ""
			(at 0 0 0)
			(layer "F.Fab")
			(effects
				(font
					(size 1.27 1.27)
				)
			)
		)
		(property "Device Type" "ISL80101IRAJZ_DFN10-G222-10136A"
			(at 0.276606 2.583688 0)
			(unlocked yes)
			(layer "F.Fab")
			(hide yes)
			(effects
				(font
					(size 0.7874 0.5842)
					(thickness 0.1524)
				)
			)
		)
		(property "User Part Number" "PARTNUM*"
			(at 0.276606 3.517646 0)
			(unlocked yes)
			(layer "Cmts.User")
			(hide yes)
			(effects
				(font
					(size 0.7874 0.5842)
					(thickness 0.1524)
				)
			)
		)
		(duplicate_pad_numbers_are_jumpers no)
		(fp_line
			(start -2.290318 -1.779016)
			(end 2.290318 -1.779016)
			(stroke
				(width 0.1)
				(type default)
			)
			(layer "F.SilkS")
		)
		(fp_line
			(start -2.290318 1.779016)
			(end -2.290318 -1.779016)
			(stroke
				(width 0.1)
				(type default)
			)
			(layer "F.SilkS")
		)
		(fp_line
			(start 2.290318 -1.779016)
			(end 2.290318 1.779016)
			(stroke
				(width 0.1)
				(type default)
			)
			(layer "F.SilkS")
		)
		(fp_line
			(start 2.290318 1.779016)
			(end -2.290318 1.779016)
			(stroke
				(width 0.1)
				(type default)
			)
			(layer "F.SilkS")
		)
		(fp_poly
			(pts
				(arc
					(start -2.553462 -1.023112)
					(mid -3.315462 -1.023112)
					(end -2.553462 -1.023112)
				)
			)
			(stroke
				(width 0)
				(type default)
			)
			(fill yes)
			(layer "F.SilkS")
		)
		(fp_poly
			(pts
				(xy -0.7239 -0.1016)
				(arc
					(start -0.7239 -0.6477)
					(mid -0.290295 -0.468095)
					(end -0.4699 -0.9017)
				)
				(xy 0.7239 -0.9017) (xy 0.7239 -0.1016)
			)
			(stroke
				(width 0)
				(type default)
			)
			(fill yes)
			(layer "F.Paste")
		)
		(fp_poly
			(pts
				(xy -0.7239 0.1016) (xy 0.7239 0.1016) (xy 0.7239 0.62992)
				(arc
					(start 0.723392 0.630428)
					(mid 0.643347 0.462032)
					(end 0.4699 0.3937)
				)
				(arc
					(start 0.4699 0.3937)
					(mid 0.290295 0.468095)
					(end 0.2159 0.6477)
				)
				(arc
					(start 0.2159 0.6477)
					(mid 0.284984 0.821833)
					(end 0.45466 0.901192)
				)
				(xy 0.45466 0.9017) (xy -0.7239 0.9017)
			)
			(stroke
				(width 0)
				(type default)
			)
			(fill yes)
			(layer "F.Paste")
		)
		(fp_poly
			(pts
				(xy -2.544318 2.033016) (xy 2.544318 2.033016) (xy 2.544318 -2.033016) (xy -2.544318 -2.033016)
			)
			(stroke
				(width 0)
				(type default)
			)
			(fill no)
			(layer "F.CrtYd")
		)
		(fp_line
			(start -1.525016 -1.525016)
			(end 1.525016 -1.525016)
			(stroke
				(width 0.1)
				(type default)
			)
			(layer "F.Fab")
		)
		(fp_line
			(start -1.525016 1.525016)
			(end -1.525016 -1.525016)
			(stroke
				(width 0.1)
				(type default)
			)
			(layer "F.Fab")
		)
		(fp_line
			(start 1.525016 -1.525016)
			(end 1.525016 1.525016)
			(stroke
				(width 0.1)
				(type default)
			)
			(layer "F.Fab")
		)
		(fp_line
			(start 1.525016 1.525016)
			(end -1.525016 1.525016)
			(stroke
				(width 0.1)
				(type default)
			)
			(layer "F.Fab")
		)
		(fp_poly
			(pts
				(arc
					(start -1.664462 -1.277112)
					(mid -2.426462 -1.277112)
					(end -1.664462 -1.277112)
				)
			)
			(stroke
				(width 0)
				(type default)
			)
			(fill yes)
			(layer "F.Fab")
		)
		(fp_text user "5"
			(at -2.921 1.41097 0)
			(unlocked yes)
			(layer "F.SilkS")
			(effects
				(font
					(size 0.7874 0.5842)
					(thickness 0.1524)
				)
			)
		)
		(fp_text user "6"
			(at 2.7559 1.202182 0)
			(unlocked yes)
			(layer "F.SilkS")
			(effects
				(font
					(size 0.7874 0.5842)
					(thickness 0.1524)
				)
			)
		)
		(fp_text user "5"
			(at -2.032 1.14427 0)
			(unlocked yes)
			(layer "F.Fab")
			(effects
				(font
					(size 0.7874 0.5842)
					(thickness 0.1524)
				)
			)
		)
		(fp_text user "6"
			(at 2.032 1.14427 0)
			(unlocked yes)
			(layer "F.Fab")
			(effects
				(font
					(size 0.7874 0.5842)
					(thickness 0.1524)
				)
			)
		)
		(fp_text user "10"
			(at 2.286 -1.39573 0)
			(unlocked yes)
			(layer "F.Fab")
			(effects
				(font
					(size 0.7874 0.5842)
					(thickness 0.1524)
				)
			)
		)
		(pad "1" smd circle
			(at -1.515618 -1.000252 180)
			(size 0 0)
			(layers "F.Cu" "F.Mask" "F.Paste")
			(net "XP2R5V_FPGA")
		)
		(pad "2" smd rect
			(at -1.515618 -0.500126)
			(size 1.0414 0.3048)
			(layers "F.Cu" "F.Mask" "F.Paste")
			(net "XP2R5V_FPGA")
		)
		(pad "3" smd rect
			(at -1.515618 0)
			(size 1.0414 0.3048)
			(layers "F.Cu" "F.Mask" "F.Paste")
			(net "UNNAMED_515_ISL80101IRAJZDFN10_")
		)
		(pad "4" smd rect
			(at -1.515618 0.500126)
			(size 1.0414 0.3048)
			(layers "F.Cu" "F.Mask" "F.Paste")
			(net "UNNAMED_515_CAPACITOR_I138_1")
		)
		(pad "5" smd circle
			(at -1.515618 1.000252)
			(size 0 0)
			(layers "F.Cu" "F.Mask" "F.Paste")
			(net "SG")
		)
		(pad "6" smd circle
			(at 1.515618 1.000252)
			(size 0 0)
			(layers "F.Cu" "F.Mask" "F.Paste")
			(net "UNNAMED_515_CAPACITOR_I132_1")
		)
		(pad "7" smd rect
			(at 1.515618 0.500126)
			(size 1.0414 0.3048)
			(layers "F.Cu" "F.Mask" "F.Paste")
			(net "UNNAMED_515_CAPACITOR_I128_1")
		)
		(pad "8" smd rect
			(at 1.515618 0)
			(size 1.0414 0.3048)
			(layers "F.Cu" "F.Mask" "F.Paste")
			(net "Net_764")
		)
		(pad "9" smd rect
			(at 1.515618 -0.500126)
			(size 1.0414 0.3048)
			(layers "F.Cu" "F.Mask" "F.Paste")
			(net "UNNAMED_515_CAPACITOR_I130_1")
		)
		(pad "10" smd circle
			(at 1.515618 -1.000252 180)
			(size 0 0)
			(layers "F.Cu" "F.Mask" "F.Paste")
			(net "UNNAMED_515_CAPACITOR_I130_1")
		)
		(pad "11" smd rect
			(at 0 0)
			(size 1.4478 1.8034)
			(layers "F.Cu" "F.Mask" "F.Paste")
			(net "SG")
		)
	)
	(footprint ""
		(layer "F.Cu")
		(at 153.049986 -107.849924 -90)
		(property "Reference" "DS10"
			(at 0.026924 -1.421384 90)
			(unlocked yes)
			(layer "F.SilkS")
			(effects
				(font
					(size 0.7874 0.5842)
					(thickness 0.1524)
				)
			)
		)
		(property "Value" ""
			(at 0 0 270)
			(layer "F.Fab")
			(effects
				(font
					(size 1.27 1.27)
				)
			)
		)
		(property "Device Type" "OPTICAL-G170-10143-01"
			(at 0.1778 1.483081 270)
			(unlocked yes)
			(layer "F.Fab")
			(hide yes)
			(effects
				(font
					(size 0.786892 0.583946)
					(thickness 0.000001)
				)
			)
		)
		(property "User Part Number" "PARTNUM*"
			(at 0.1778 2.422881 270)
			(unlocked yes)
			(layer "Cmts.User")
			(hide yes)
			(effects
				(font
					(size 0.786892 0.583946)
					(thickness 0.000001)
				)
			)
		)
		(duplicate_pad_numbers_are_jumpers no)
		(fp_line
			(start -1.1938 1.0922)
			(end -2.4638 1.0922)
			(stroke
				(width 0.1)
				(type default)
			)
			(layer "F.SilkS")
		)
		(fp_line
			(start -1.397508 0.704088)
			(end -1.397508 -0.704088)
			(stroke
				(width 0.1)
				(type default)
			)
			(layer "F.SilkS")
		)
		(fp_line
			(start 1.397508 0.704088)
			(end -1.397508 0.704088)
			(stroke
				(width 0.1)
				(type default)
			)
			(layer "F.SilkS")
		)
		(fp_line
			(start -1.8288 0.4572)
			(end -1.8288 1.7272)
			(stroke
				(width 0.1)
				(type default)
			)
			(layer "F.SilkS")
		)
		(fp_line
			(start -1.397508 -0.704088)
			(end 1.397508 -0.704088)
			(stroke
				(width 0.1)
				(type default)
			)
			(layer "F.SilkS")
		)
		(fp_line
			(start 1.397508 -0.704088)
			(end 1.397508 0.704088)
			(stroke
				(width 0.1)
				(type default)
			)
			(layer "F.SilkS")
		)
		(fp_rect
			(start 1.905508 0.704088)
			(end 1.397508 -0.704088)
			(stroke
				(width 0)
				(type default)
			)
			(fill yes)
			(layer "F.SilkS")
		)
		(fp_rect
			(start 1.905508 0.958088)
			(end -1.651508 -0.958088)
			(stroke
				(width 0)
				(type default)
			)
			(fill no)
			(layer "F.CrtYd")
		)
		(fp_line
			(start -1.0668 1.2192)
			(end -2.3368 1.2192)
			(stroke
				(width 0.1)
				(type default)
			)
			(layer "F.Fab")
		)
		(fp_line
			(start -1.7018 0.5842)
			(end -1.7018 1.8542)
			(stroke
				(width 0.1)
				(type default)
			)
			(layer "F.Fab")
		)
		(fp_line
			(start -0.850138 0.450088)
			(end 0.850138 0.450088)
			(stroke
				(width 0.1)
				(type default)
			)
			(layer "F.Fab")
		)
		(fp_line
			(start 0.850138 0.450088)
			(end 0.850138 -0.450088)
			(stroke
				(width 0.1)
				(type default)
			)
			(layer "F.Fab")
		)
		(fp_line
			(start -0.850138 -0.450088)
			(end -0.850138 0.450088)
			(stroke
				(width 0.1)
				(type default)
			)
			(layer "F.Fab")
		)
		(fp_line
			(start 0.850138 -0.450088)
			(end -0.850138 -0.450088)
			(stroke
				(width 0.1)
				(type default)
			)
			(layer "F.Fab")
		)
		(fp_rect
			(start 0.850138 0.450088)
			(end 0.342138 -0.450088)
			(stroke
				(width 0)
				(type default)
			)
			(fill yes)
			(layer "F.Fab")
		)
		(fp_text user "C"
			(at 1.404874 1.284986 0)
			(unlocked yes)
			(layer "F.SilkS")
			(effects
				(font
					(size 0.635 0.4064)
					(thickness 0.1524)
				)
			)
		)
		(fp_text user "A"
			(at -1.846326 0.014986 0)
			(unlocked yes)
			(layer "F.SilkS")
			(effects
				(font
					(size 0.635 0.4064)
					(thickness 0.1524)
				)
			)
		)
		(fp_text user "A"
			(at -2.346706 0.141986 0)
			(unlocked yes)
			(layer "F.Fab")
			(effects
				(font
					(size 0.7874 0.5842)
					(thickness 0.1524)
				)
			)
		)
		(fp_text user "C"
			(at 0.828294 -1.001014 0)
			(unlocked yes)
			(layer "F.Fab")
			(effects
				(font
					(size 0.7874 0.5842)
					(thickness 0.1524)
				)
			)
		)
		(pad "A" smd rect
			(at -0.749808 0 270)
			(size 0.7874 0.7874)
			(layers "F.Cu" "F.Mask" "F.Paste")
			(net "UNNAMED_14_OPTICAL_I138_A")
		)
		(pad "C" smd rect
			(at 0.749808 0 270)
			(size 0.7874 0.7874)
			(layers "F.Cu" "F.Mask" "F.Paste")
			(net "FPGA_USR_LED1")
		)
	)
	(footprint ""
		(layer "F.Cu")
		(at 113.157 -68.707 -90)
		(property "Reference" "C232"
			(at -0.381 -2.96037 90)
			(unlocked yes)
			(layer "F.SilkS")
			(effects
				(font
					(size 0.7874 0.5842)
					(thickness 0.1524)
				)
			)
		)
		(property "Value" "VAL*"
			(at 0.0762 3.134106 270)
			(unlocked yes)
			(layer "F.Fab")
			(hide yes)
			(effects
				(font
					(size 0.7874 0.5842)
					(thickness 0.1524)
				)
			)
		)
		(property "Tolerance" "TOL*"
			(at 0.0762 4.048506 270)
			(unlocked yes)
			(layer "Cmts.User")
			(hide yes)
			(effects
				(font
					(size 0.7874 0.5842)
					(thickness 0.1524)
				)
			)
		)
		(property "User Part Number" "PARTNUM*"
			(at 0.1016 5.013706 270)
			(unlocked yes)
			(layer "Cmts.User")
			(hide yes)
			(effects
				(font
					(size 0.7874 0.5842)
					(thickness 0.1524)
				)
			)
		)
		(property "Device Type" "CAPACITOR-G107-0F226-CM,22UF,2A"
			(at 0.0508 2.194306 270)
			(unlocked yes)
			(layer "F.Fab")
			(hide yes)
			(effects
				(font
					(size 0.7874 0.5842)
					(thickness 0.1524)
				)
			)
		)
		(duplicate_pad_numbers_are_jumpers no)
		(fp_line
			(start -1.5748 0.9398)
			(end 1.5748 0.9398)
			(stroke
				(width 0.1)
				(type default)
			)
			(layer "F.SilkS")
		)
		(fp_line
			(start 1.5748 0.9398)
			(end 1.5748 -0.9398)
			(stroke
				(width 0.1)
				(type default)
			)
			(layer "F.SilkS")
		)
		(fp_line
			(start -1.5748 -0.9398)
			(end -1.5748 0.9398)
			(stroke
				(width 0.1)
				(type default)
			)
			(layer "F.SilkS")
		)
		(fp_line
			(start 1.5748 -0.9398)
			(end -1.5748 -0.9398)
			(stroke
				(width 0.1)
				(type default)
			)
			(layer "F.SilkS")
		)
		(fp_rect
			(start 1.5748 -0.9398)
			(end -1.5748 0.9398)
			(stroke
				(width 0)
				(type default)
			)
			(fill no)
			(layer "F.CrtYd")
		)
		(fp_line
			(start -1.016 0.635)
			(end 1.016 0.635)
			(stroke
				(width 0.1)
				(type default)
			)
			(layer "F.Fab")
		)
		(fp_line
			(start 1.016 0.635)
			(end 1.016 -0.635)
			(stroke
				(width 0.1)
				(type default)
			)
			(layer "F.Fab")
		)
		(fp_line
			(start -1.016 -0.635)
			(end -1.016 0.635)
			(stroke
				(width 0.1)
				(type default)
			)
			(layer "F.Fab")
		)
		(fp_line
			(start 1.016 -0.635)
			(end -1.016 -0.635)
			(stroke
				(width 0.1)
				(type default)
			)
			(layer "F.Fab")
		)
		(pad "1" smd rect
			(at -0.8382 0 270)
			(size 0.9652 1.3716)
			(layers "F.Cu" "F.Mask" "F.Paste")
			(net "XP3R3V")
		)
		(pad "2" smd rect
			(at 0.8382 0 270)
			(size 0.9652 1.3716)
			(layers "F.Cu" "F.Mask" "F.Paste")
			(net "SG")
		)
		(zone
			(layer "F.Cu")
			(hatch none 0.5)
			(connect_pads
				(clearance 0)
			)
			(min_thickness 0.25)
			(keepout
				(tracks allowed)
				(vias not_allowed)
				(pads allowed)
				(copperpour not_allowed)
				(footprints allowed)
			)
			(placement
				(enabled no)
				(sheetname "")
			)
			(fill
				(thermal_gap 0.5)
				(thermal_bridge_width 0.5)
				(island_removal_mode 0)
			)
			(polygon
				(pts
					(xy 113.792 -68.4784) (xy 113.792 -68.9356) (xy 112.522 -68.9356) (xy 112.522 -68.4784)
				)
			)
		)
	)
)
